# T6G (Grand Teton) — schematic netlist excerpt (pin names and nets, part order shuffled) for the footprints in the layout excerpt that follows; sources: Cadence DE-HDL packaged netlist, KiCad conversion of 04192023_DAF0TMB3IC0_F0TG_MB_C_brd_V02_OCP.brd

C6067  Q_CAP  0.001UF 50V 10% X7R  pkg C0402  page 177 : A = P1V2_AUX ; B = GND
R4605  Q_RES  1K 1% CHIP  pkg 0402LF  page 253 : A = P3V3_AUX ; B = PWRGD_PS_PWROK_PLD_ISO

(kicad_pcb
	(version 20260206)
	(generator "pcbnew")
	(generator_version "10.0")
	(general
		(thickness 1.6)
		(legacy_teardrops no)
	)
	(paper "A4")
	(title_block
		(title "04192023_DAF0TMB3IC0_F0TG_MB_C_brd_V02_OCP.brd")
		(comment 1 "Grand Teton / footprints 7719-7721 of 8354")
	)
	(layers
		(0 "F.Cu" signal "TOP")
		(4 "In1.Cu" signal "GND")
		(6 "In2.Cu" signal "IN1")
		(8 "In3.Cu" signal "GND1")
		(10 "In4.Cu" signal "IN2")
		(12 "In5.Cu" signal "GND2")
		(14 "In6.Cu" signal "IN3")
		(16 "In7.Cu" signal "GND3")
		(18 "In8.Cu" signal "VCC")
		(20 "In9.Cu" signal "VCC1")
		(22 "In10.Cu" signal "GND4")
		(24 "In11.Cu" signal "IN4")
		(26 "In12.Cu" signal "GND5")
		(28 "In13.Cu" signal "IN5")
		(30 "In14.Cu" signal "GND6")
		(32 "In15.Cu" signal "IN6")
		(34 "In16.Cu" signal "GND7")
		(2 "B.Cu" signal "BOTTOM")
		(9 "F.Adhes" user "F.Adhesive")
		(11 "B.Adhes" user "B.Adhesive")
		(13 "F.Paste" user "Package Geometry/Pastemask Top")
		(15 "B.Paste" user "Package Geometry/Pastemask Bottom")
		(5 "F.SilkS" user "Ref Des/Silkscreen Top")
		(7 "B.SilkS" user "Ref Des/Silkscreen Bottom")
		(1 "F.Mask" user "Board Geometry/Soldermask Top")
		(3 "B.Mask" user "Board Geometry/Soldermask Bottom")
		(17 "Dwgs.User" user "User.Drawings")
		(19 "Cmts.User" user "User.Comments")
		(21 "Eco1.User" user "User.Eco1")
		(23 "Eco2.User" user "User.Eco2")
		(25 "Edge.Cuts" user "Board Geometry/Outline")
		(27 "Margin" user)
		(31 "F.CrtYd" user "Package Geometry/Place Bound Top")
		(29 "B.CrtYd" user "Package Geometry/Place Bound Bottom")
		(35 "F.Fab" user "Ref Des/Assembly Top")
		(33 "B.Fab" user "Ref Des/Assembly Bottom")
	)
	(footprint ""
		(layer "B.Cu")
		(at 136.040114 -37.898578)
		(property "Reference" "C6067"
			(at 0 0 0)
			(layer "B.SilkS")
			(hide yes)
			(effects
				(font
					(size 1.27 1.27)
				)
				(justify mirror)
			)
		)
		(property "Value" ""
			(at 0 0 0)
			(layer "B.Fab")
			(effects
				(font
					(size 1.27 1.27)
				)
				(justify mirror)
			)
		)
		(duplicate_pad_numbers_are_jumpers no)
		(fp_line
			(start -0.7874 -0.4064)
			(end -0.7874 0.4064)
			(stroke
				(width 0.1524)
				(type default)
			)
			(layer "B.SilkS")
		)
		(fp_line
			(start -0.7874 0.4064)
			(end 0.7874 0.4064)
			(stroke
				(width 0.1524)
				(type default)
			)
			(layer "B.SilkS")
		)
		(fp_line
			(start 0.7874 -0.4064)
			(end -0.7874 -0.4064)
			(stroke
				(width 0.1524)
				(type default)
			)
			(layer "B.SilkS")
		)
		(fp_line
			(start 0.7874 0.4064)
			(end 0.7874 -0.4064)
			(stroke
				(width 0.1524)
				(type default)
			)
			(layer "B.SilkS")
		)
		(fp_line
			(start -0.67945 -0.3048)
			(end -0.67945 0.3048)
			(stroke
				(width 0.1)
				(type default)
			)
			(layer "B.Fab")
		)
		(fp_line
			(start -0.67945 0.3048)
			(end -0.120396 0.3048)
			(stroke
				(width 0.1)
				(type default)
			)
			(layer "B.Fab")
		)
		(fp_line
			(start -0.12065 -0.3048)
			(end -0.67945 -0.3048)
			(stroke
				(width 0.1)
				(type default)
			)
			(layer "B.Fab")
		)
		(fp_line
			(start -0.12065 -0.2794)
			(end -0.12065 -0.3048)
			(stroke
				(width 0.1)
				(type default)
			)
			(layer "B.Fab")
		)
		(fp_line
			(start -0.120396 0.2794)
			(end 0.12065 0.2794)
			(stroke
				(width 0.1)
				(type default)
			)
			(layer "B.Fab")
		)
		(fp_line
			(start -0.120396 0.3048)
			(end -0.120396 0.2794)
			(stroke
				(width 0.1)
				(type default)
			)
			(layer "B.Fab")
		)
		(fp_line
			(start 0.12065 -0.305054)
			(end 0.12065 -0.2794)
			(stroke
				(width 0.1)
				(type default)
			)
			(layer "B.Fab")
		)
		(fp_line
			(start 0.12065 -0.2794)
			(end -0.12065 -0.2794)
			(stroke
				(width 0.1)
				(type default)
			)
			(layer "B.Fab")
		)
		(fp_line
			(start 0.12065 0.2794)
			(end 0.12065 0.3048)
			(stroke
				(width 0.1)
				(type default)
			)
			(layer "B.Fab")
		)
		(fp_line
			(start 0.12065 0.3048)
			(end 0.67945 0.3048)
			(stroke
				(width 0.1)
				(type default)
			)
			(layer "B.Fab")
		)
		(fp_line
			(start 0.67945 -0.305054)
			(end 0.12065 -0.305054)
			(stroke
				(width 0.1)
				(type default)
			)
			(layer "B.Fab")
		)
		(fp_line
			(start 0.67945 0.3048)
			(end 0.67945 -0.305054)
			(stroke
				(width 0.1)
				(type default)
			)
			(layer "B.Fab")
		)
		(pad "1" smd circle
			(at 0.40005 0 180)
			(size 0 0)
			(layers "B.Cu" "B.Mask" "B.Paste")
			(net "P1V2_AUX")
		)
		(pad "2" smd circle
			(at -0.40005 0 180)
			(size 0 0)
			(layers "B.Cu" "B.Mask" "B.Paste")
			(net "GND")
		)
	)
	(footprint ""
		(layer "B.Cu")
		(at 234.952286 -257.70713 180)
		(property "Reference" ""
			(at 0 0 0)
			(layer "B.SilkS")
			(hide yes)
			(effects
				(font
					(size 1.27 1.27)
				)
				(justify mirror)
			)
		)
		(property "Value" ""
			(at 0 0 0)
			(layer "B.Fab")
			(effects
				(font
					(size 1.27 1.27)
				)
				(justify mirror)
			)
		)
		(duplicate_pad_numbers_are_jumpers no)
		(pad "1" smd circle
			(at 0 0)
			(size 0.9906 0.9906)
			(layers "B.Cu" "B.Mask" "B.Paste")
			(net "Net_46")
		)
		(zone
			(layer "B.Cu")
			(hatch none 0.5)
			(connect_pads
				(clearance 0)
			)
			(min_thickness 0.25)
			(keepout
				(tracks not_allowed)
				(vias allowed)
				(pads allowed)
				(copperpour not_allowed)
				(footprints allowed)
			)
			(placement
				(enabled no)
				(sheetname "")
			)
			(fill
				(thermal_gap 0.5)
				(thermal_bridge_width 0.5)
				(island_removal_mode 0)
			)
			(polygon
				(pts
					(arc
						(start 236.577886 -257.70713)
						(mid 233.326686 -257.70713)
						(end 236.577886 -257.70713)
					)
				)
			)
		)
	)
	(footprint ""
		(layer "B.Cu")
		(at 310.411876 -78.775814 90)
		(property "Reference" "R4605"
			(at 0 0 90)
			(layer "B.SilkS")
			(hide yes)
			(effects
				(font
					(size 1.27 1.27)
				)
				(justify mirror)
			)
		)
		(property "Value" ""
			(at 0 0 90)
			(layer "B.Fab")
			(effects
				(font
					(size 1.27 1.27)
				)
				(justify mirror)
			)
		)
		(duplicate_pad_numbers_are_jumpers no)
		(fp_line
			(start 0.7874 -0.4064)
			(end -0.7874 -0.4064)
			(stroke
				(width 0.1524)
				(type default)
			)
			(layer "B.SilkS")
		)
		(fp_line
			(start -0.7874 -0.4064)
			(end -0.7874 0.4064)
			(stroke
				(width 0.1524)
				(type default)
			)
			(layer "B.SilkS")
		)
		(fp_line
			(start 0.7874 0.4064)
			(end 0.7874 -0.4064)
			(stroke
				(width 0.1524)
				(type default)
			)
			(layer "B.SilkS")
		)
		(fp_line
			(start -0.7874 0.4064)
			(end 0.7874 0.4064)
			(stroke
				(width 0.1524)
				(type default)
			)
			(layer "B.SilkS")
		)
		(fp_line
			(start 0.67945 -0.305054)
			(end 0.12065 -0.305054)
			(stroke
				(width 0.1)
				(type default)
			)
			(layer "B.Fab")
		)
		(fp_line
			(start 0.12065 -0.305054)
			(end 0.12065 -0.2794)
			(stroke
				(width 0.1)
				(type default)
			)
			(layer "B.Fab")
		)
		(fp_line
			(start -0.12065 -0.3048)
			(end -0.67945 -0.3048)
			(stroke
				(width 0.1)
				(type default)
			)
			(layer "B.Fab")
		)
		(fp_line
			(start -0.67945 -0.3048)
			(end -0.67945 0.3048)
			(stroke
				(width 0.1)
				(type default)
			)
			(layer "B.Fab")
		)
		(fp_line
			(start 0.12065 -0.2794)
			(end -0.12065 -0.2794)
			(stroke
				(width 0.1)
				(type default)
			)
			(layer "B.Fab")
		)
		(fp_line
			(start -0.12065 -0.2794)
			(end -0.12065 -0.3048)
			(stroke
				(width 0.1)
				(type default)
			)
			(layer "B.Fab")
		)
		(fp_line
			(start 0.12065 0.2794)
			(end 0.12065 0.3048)
			(stroke
				(width 0.1)
				(type default)
			)
			(layer "B.Fab")
		)
		(fp_line
			(start -0.120396 0.2794)
			(end 0.12065 0.2794)
			(stroke
				(width 0.1)
				(type default)
			)
			(layer "B.Fab")
		)
		(fp_line
			(start 0.67945 0.3048)
			(end 0.67945 -0.305054)
			(stroke
				(width 0.1)
				(type default)
			)
			(layer "B.Fab")
		)
		(fp_line
			(start 0.12065 0.3048)
			(end 0.67945 0.3048)
			(stroke
				(width 0.1)
				(type default)
			)
			(layer "B.Fab")
		)
		(fp_line
			(start -0.120396 0.3048)
			(end -0.120396 0.2794)
			(stroke
				(width 0.1)
				(type default)
			)
			(layer "B.Fab")
		)
		(fp_line
			(start -0.67945 0.3048)
			(end -0.120396 0.3048)
			(stroke
				(width 0.1)
				(type default)
			)
			(layer "B.Fab")
		)
		(pad "1" smd circle
			(at 0.40005 0 270)
			(size 0 0)
			(layers "B.Cu" "B.Mask" "B.Paste")
			(net "P3V3_AUX")
		)
		(pad "2" smd circle
			(at -0.40005 0 270)
			(size 0 0)
			(layers "B.Cu" "B.Mask" "B.Paste")
			(net "PWRGD_PS_PWROK_PLD_ISO")
		)
	)
)
